(kicad_pcb
	(version 20241229)
	(generator "pcbnew")
	(generator_version "9.0")
	(general
		(thickness 1.599998)
		(legacy_teardrops no)
	)
	(paper "A4")
	(title_block
		(date "2023-02-12")
		(rev "1.1.5")
		(comment 9 "footprints 281-286 of 473")
	)
	(layers
		(0 "F.Cu" signal)
		(4 "In1.Cu" power "In1.GND")
		(6 "In2.Cu" signal)
		(8 "In3.Cu" power "In3.GND")
		(10 "In4.Cu" power "In4.VCC")
		(12 "In5.Cu" signal)
		(14 "In6.Cu" power "In6.VCC")
		(2 "B.Cu" signal)
		(9 "F.Adhes" user "F.Adhesive")
		(11 "B.Adhes" user "B.Adhesive")
		(13 "F.Paste" user)
		(15 "B.Paste" user)
		(5 "F.SilkS" user "F.Silkscreen")
		(7 "B.SilkS" user "B.Silkscreen")
		(1 "F.Mask" user)
		(3 "B.Mask" user)
		(17 "Dwgs.User" user "User.Drawings")
		(19 "Cmts.User" user "User.Comments")
		(21 "Eco1.User" user "User.Eco1")
		(23 "Eco2.User" user "User.Eco2")
		(25 "Edge.Cuts" user)
		(27 "Margin" user)
		(31 "F.CrtYd" user "F.Courtyard")
		(29 "B.CrtYd" user "B.Courtyard")
		(35 "F.Fab" user)
		(33 "B.Fab" user)
	)
	(footprint "antmicro-footprints:R_0402_1005Metric"
		(layer "F.Cu")
		(at 137.6 59.7)
		(descr "Resistor SMD 0402")
		(tags "resistor SMD 0402")
		(property "Reference" "R153"
			(at -0.9 -0.5 0)
			(layer "F.SilkS")
			(effects
				(font
					(size 0.7 0.7)
					(thickness 0.15)
				)
				(justify left bottom)
			)
		)
		(property "Value" "R_10k_0402"
			(at 0 1.4 0)
			(layer "F.Fab")
			(effects
				(font
					(size 0.7 0.7)
					(thickness 0.15)
				)
				(justify left bottom)
			)
		)
		(property "Description" "10k resistor in 0402 package with 1% tolerance"
			(at 0 0 0)
			(layer "F.Fab")
			(hide yes)
			(effects
				(font
					(size 1.27 1.27)
					(thickness 0.15)
				)
			)
		)
		(property "Author" "Antmicro"
			(at 0 0 0)
			(layer "F.Fab")
			(hide yes)
			(effects
				(font
					(size 1 1)
					(thickness 0.15)
				)
			)
		)
		(property "License" "Apache-2.0"
			(at 0 0 0)
			(layer "F.Fab")
			(hide yes)
			(effects
				(font
					(size 1 1)
					(thickness 0.15)
				)
			)
		)
		(property "MPN" "CR0402-FX-1002GLF"
			(at 0 0 0)
			(layer "F.Fab")
			(hide yes)
			(effects
				(font
					(size 1 1)
					(thickness 0.15)
				)
			)
		)
		(property "Manufacturer" "Bourns"
			(at 0 0 0)
			(layer "F.Fab")
			(hide yes)
			(effects
				(font
					(size 1 1)
					(thickness 0.15)
				)
			)
		)
		(property "Tolerance" "1%"
			(at 0 0 0)
			(layer "F.Fab")
			(hide yes)
			(effects
				(font
					(size 1 1)
					(thickness 0.15)
				)
			)
		)
		(property "Val" "10k"
			(at 0 0 0)
			(layer "F.Fab")
			(hide yes)
			(effects
				(font
					(size 1 1)
					(thickness 0.15)
				)
			)
		)
		(sheetname "Supply")
		(sheetfile "supply.kicad_sch")
		(attr smd)
		(fp_rect
			(start -0.93 -0.47)
			(end 0.93 0.47)
			(stroke
				(width 0.05)
				(type solid)
			)
			(fill no)
			(layer "F.CrtYd")
		)
		(fp_rect
			(start -0.5 -0.25)
			(end 0.5 0.25)
			(stroke
				(width 0.15)
				(type solid)
			)
			(fill no)
			(layer "F.Fab")
		)
		(pad "1" smd roundrect
			(at -0.485 0)
			(size 0.59 0.64)
			(layers "F.Cu" "F.Mask" "F.Paste")
			(roundrect_rratio 0.25)
			(net 636 "/Supply/0V6_EN")
			(pintype "passive")
		)
		(pad "2" smd roundrect
			(at 0.485 0)
			(size 0.59 0.64)
			(layers "F.Cu" "F.Mask" "F.Paste")
			(roundrect_rratio 0.25)
			(net 5 "GND")
			(pintype "passive")
		)
	)
	(footprint "antmicro-footprints:R_0402_1005Metric"
		(layer "F.Cu")
		(at 186.1 111.85 -90)
		(descr "Resistor SMD 0402")
		(tags "resistor SMD 0402")
		(property "Reference" "R152"
			(at -0.75 -0.4 270)
			(layer "F.SilkS")
			(effects
				(font
					(size 0.7 0.7)
					(thickness 0.15)
				)
				(justify left bottom)
			)
		)
		(property "Value" "R_0R_0402"
			(at 0 1.4 270)
			(layer "F.Fab")
			(effects
				(font
					(size 0.7 0.7)
					(thickness 0.15)
				)
				(justify left bottom)
			)
		)
		(property "Description" "0R resistor in 0402 package with unspecified tolerance"
			(at 0 0 270)
			(layer "F.Fab")
			(hide yes)
			(effects
				(font
					(size 1.27 1.27)
					(thickness 0.15)
				)
			)
		)
		(property "Author" "Antmicro"
			(at 74.25 297.95 0)
			(layer "F.Fab")
			(hide yes)
			(effects
				(font
					(size 1 1)
					(thickness 0.15)
				)
			)
		)
		(property "Current" "1A"
			(at 74.25 297.95 0)
			(layer "F.Fab")
			(hide yes)
			(effects
				(font
					(size 1 1)
					(thickness 0.15)
				)
			)
		)
		(property "License" "Apache-2.0"
			(at 74.25 297.95 0)
			(layer "F.Fab")
			(hide yes)
			(effects
				(font
					(size 1 1)
					(thickness 0.15)
				)
			)
		)
		(property "MPN" "ERJ2GE0R00X"
			(at 74.25 297.95 0)
			(layer "F.Fab")
			(hide yes)
			(effects
				(font
					(size 1 1)
					(thickness 0.15)
				)
			)
		)
		(property "Manufacturer" "Panasonic"
			(at 74.25 297.95 0)
			(layer "F.Fab")
			(hide yes)
			(effects
				(font
					(size 1 1)
					(thickness 0.15)
				)
			)
		)
		(property "Tolerance" ""
			(at 74.25 297.95 0)
			(layer "F.Fab")
			(hide yes)
			(effects
				(font
					(size 1 1)
					(thickness 0.15)
				)
			)
		)
		(property "Val" "0R"
			(at 74.25 297.95 0)
			(layer "F.Fab")
			(hide yes)
			(effects
				(font
					(size 1 1)
					(thickness 0.15)
				)
			)
		)
		(sheetname "Supply")
		(sheetfile "supply.kicad_sch")
		(attr smd)
		(fp_rect
			(start -0.93 -0.47)
			(end 0.93 0.47)
			(stroke
				(width 0.05)
				(type solid)
			)
			(fill no)
			(layer "F.CrtYd")
		)
		(fp_rect
			(start -0.5 -0.25)
			(end 0.5 0.25)
			(stroke
				(width 0.15)
				(type solid)
			)
			(fill no)
			(layer "F.Fab")
		)
		(pad "1" smd roundrect
			(at -0.485 0 270)
			(size 0.59 0.64)
			(layers "F.Cu" "F.Mask" "F.Paste")
			(roundrect_rratio 0.25)
			(net 5 "GND")
			(pintype "passive")
		)
		(pad "2" smd roundrect
			(at 0.485 0 270)
			(size 0.59 0.64)
			(layers "F.Cu" "F.Mask" "F.Paste")
			(roundrect_rratio 0.25)
			(net 624 "/Supply/1V2_SS{slash}TR")
			(pintype "passive")
		)
	)
	(footprint "antmicro-footprints:SOT-523"
		(layer "F.Cu")
		(at 142.3825 89.599 90)
		(property "Reference" "Q8"
			(at 0.599 -1.9825 0)
			(layer "F.SilkS")
			(effects
				(font
					(size 0.7 0.7)
					(thickness 0.15)
				)
				(justify left bottom)
			)
		)
		(property "Value" "DMG1012T-7"
			(at 0.1 1.824 90)
			(layer "F.Fab")
			(effects
				(font
					(size 0.7 0.7)
					(thickness 0.15)
				)
				(justify left bottom)
			)
		)
		(property "Author" "Antmicro"
			(at 231.9815 -52.7835 0)
			(layer "F.Fab")
			(hide yes)
			(effects
				(font
					(size 1 1)
					(thickness 0.15)
				)
			)
		)
		(property "License" "Apache-2.0"
			(at 231.9815 -52.7835 0)
			(layer "F.Fab")
			(hide yes)
			(effects
				(font
					(size 1 1)
					(thickness 0.15)
				)
			)
		)
		(property "MPN" "DMG1012T-7"
			(at 231.9815 -52.7835 0)
			(layer "F.Fab")
			(hide yes)
			(effects
				(font
					(size 1 1)
					(thickness 0.15)
				)
			)
		)
		(property "Manufacturer" "Diodes Incorporated"
			(at 231.9815 -52.7835 0)
			(layer "F.Fab")
			(hide yes)
			(effects
				(font
					(size 1 1)
					(thickness 0.15)
				)
			)
		)
		(sheetname "Supply")
		(sheetfile "supply.kicad_sch")
		(attr smd)
		(fp_line
			(start -0.277 -0.551)
			(end -0.277 -0.75)
			(stroke
				(width 0.15)
				(type solid)
			)
			(layer "F.SilkS")
		)
		(fp_line
			(start -0.725 -0.551)
			(end -0.277 -0.551)
			(stroke
				(width 0.15)
				(type solid)
			)
			(layer "F.SilkS")
		)
		(fp_line
			(start -0.927 -0.351)
			(end -0.725 -0.551)
			(stroke
				(width 0.15)
				(type solid)
			)
			(layer "F.SilkS")
		)
		(fp_line
			(start -0.927 -0.051)
			(end -0.927 -0.351)
			(stroke
				(width 0.15)
				(type solid)
			)
			(layer "F.SilkS")
		)
		(fp_circle
			(center -0.9652 0.9652)
			(end -0.9152 0.9652)
			(stroke
				(width 0.15)
				(type solid)
			)
			(fill yes)
			(layer "F.SilkS")
		)
		(fp_line
			(start 1.1 -1.16)
			(end 1.1 1.15)
			(stroke
				(width 0.05)
				(type solid)
			)
			(layer "F.CrtYd")
		)
		(fp_line
			(start -1.12 -1.16)
			(end 1.1 -1.16)
			(stroke
				(width 0.05)
				(type solid)
			)
			(layer "F.CrtYd")
		)
		(fp_line
			(start -1.12 -1.16)
			(end -1.12 1.15)
			(stroke
				(width 0.05)
				(type solid)
			)
			(layer "F.CrtYd")
		)
		(fp_line
			(start -1.12 1.15)
			(end 1.1 1.15)
			(stroke
				(width 0.05)
				(type solid)
			)
			(layer "F.CrtYd")
		)
		(fp_line
			(start 0.8 -0.425)
			(end -0.652 -0.425)
			(stroke
				(width 0.15)
				(type solid)
			)
			(layer "F.Fab")
		)
		(fp_line
			(start 0.8 -0.425)
			(end 0.8 0.424)
			(stroke
				(width 0.15)
				(type solid)
			)
			(layer "F.Fab")
		)
		(fp_line
			(start -0.652 -0.425)
			(end -0.802 -0.276)
			(stroke
				(width 0.15)
				(type solid)
			)
			(layer "F.Fab")
		)
		(fp_line
			(start -0.802 -0.276)
			(end -0.802 0.424)
			(stroke
				(width 0.15)
				(type solid)
			)
			(layer "F.Fab")
		)
		(fp_line
			(start 0.8 0.424)
			(end -0.802 0.424)
			(stroke
				(width 0.15)
				(type solid)
			)
			(layer "F.Fab")
		)
		(fp_circle
			(center -0.9652 0.9652)
			(end -0.9144 0.9652)
			(stroke
				(width 0.15)
				(type solid)
			)
			(fill no)
			(layer "F.Fab")
		)
		(pad "1" smd rect
			(at -0.5 0.65 90)
			(size 0.4 0.51)
			(layers "F.Cu" "F.Mask" "F.Paste")
			(net 602 "1V2_SYS")
			(pinfunction "G")
			(pintype "bidirectional")
		)
		(pad "2" smd rect
			(at 0.498 0.65 90)
			(size 0.4 0.51)
			(layers "F.Cu" "F.Mask" "F.Paste")
			(net 5 "GND")
			(pinfunction "S")
			(pintype "bidirectional")
		)
		(pad "3" smd rect
			(at 0 -0.652 90)
			(size 0.4 0.51)
			(layers "F.Cu" "F.Mask" "F.Paste")
			(net 234 "Net-(Q8-D)")
			(pinfunction "D")
			(pintype "bidirectional")
		)
	)
	(footprint "antmicro-footprints:WSON-8_6x8x0.5mm_P1.27mm"
		(layer "F.Cu")
		(at 174.475 117.625)
		(property "Reference" "U5"
			(at -4.275 -3.425 0)
			(layer "F.SilkS")
			(effects
				(font
					(size 0.7 0.7)
					(thickness 0.15)
				)
				(justify left bottom)
			)
		)
		(property "Value" "S25FL128LAGNFA010"
			(at 0 4.3 0)
			(layer "F.Fab")
			(effects
				(font
					(size 0.7 0.7)
					(thickness 0.15)
				)
				(justify left bottom)
			)
		)
		(property "Description" "FLASH - NOR Memory IC 128Mb (16M x 8) SPI - Quad I/O, QPI 133 MHz 8-WSON (5x6)"
			(at 0 0 0)
			(layer "F.Fab")
			(hide yes)
			(effects
				(font
					(size 1.27 1.27)
					(thickness 0.15)
				)
			)
		)
		(property "Author" "Antmicro"
			(at 0 0 0)
			(layer "F.Fab")
			(hide yes)
			(effects
				(font
					(size 1 1)
					(thickness 0.15)
				)
			)
		)
		(property "License" "Apache-2.0"
			(at 0 0 0)
			(layer "F.Fab")
			(hide yes)
			(effects
				(font
					(size 1 1)
					(thickness 0.15)
				)
			)
		)
		(property "MPN" "S25FL128LAGNFA010"
			(at 0 0 0)
			(layer "F.Fab")
			(hide yes)
			(effects
				(font
					(size 1 1)
					(thickness 0.15)
				)
			)
		)
		(property "Manufacturer" "Cypress Semiconductor"
			(at 0 0 0)
			(layer "F.Fab")
			(hide yes)
			(effects
				(font
					(size 1 1)
					(thickness 0.15)
				)
			)
		)
		(sheetname "Config SPI flash")
		(sheetfile "config-spi.kicad_sch")
		(attr smd)
		(fp_line
			(start 4 -3.2)
			(end -3.975 -3.2)
			(stroke
				(width 0.15)
				(type solid)
			)
			(layer "F.SilkS")
		)
		(fp_line
			(start 4.0005 3.2)
			(end -3.9995 3.2)
			(stroke
				(width 0.15)
				(type solid)
			)
			(layer "F.SilkS")
		)
		(fp_circle
			(center -4.2 -2.4)
			(end -4.149 -2.4)
			(stroke
				(width 0.15)
				(type solid)
			)
			(fill yes)
			(layer "F.SilkS")
		)
		(fp_rect
			(start -4.7 -3.25)
			(end 4.7 3.25)
			(stroke
				(width 0.05)
				(type solid)
			)
			(fill no)
			(layer "F.CrtYd")
		)
		(fp_line
			(start -3.9995 3.0005)
			(end -3.9995 -1.9995)
			(stroke
				(width 0.15)
				(type solid)
			)
			(layer "F.Fab")
		)
		(fp_line
			(start -3.0015 -2.9995)
			(end -3.9995 -1.9995)
			(stroke
				(width 0.15)
				(type solid)
			)
			(layer "F.Fab")
		)
		(fp_line
			(start -3.0015 -2.9995)
			(end 3.9995 -2.9995)
			(stroke
				(width 0.15)
				(type solid)
			)
			(layer "F.Fab")
		)
		(fp_line
			(start 3.9995 -2.9995)
			(end 3.9995 3.0005)
			(stroke
				(width 0.15)
				(type solid)
			)
			(layer "F.Fab")
		)
		(fp_line
			(start 3.9995 3.0005)
			(end -3.9995 3.0005)
			(stroke
				(width 0.15)
				(type solid)
			)
			(layer "F.Fab")
		)
		(pad "1" smd roundrect
			(at -3.9995 -1.9045 270)
			(size 0.4 1.3)
			(layers "F.Cu" "F.Mask" "F.Paste")
			(roundrect_rratio 0.25)
			(net 255 "Net-(U5-*CS)")
			(pinfunction "*CS")
			(pintype "input")
		)
		(pad "2" smd roundrect
			(at -3.9995 -0.6355 270)
			(size 0.4 1.3)
			(layers "F.Cu" "F.Mask" "F.Paste")
			(roundrect_rratio 0.25)
			(net 260 "Net-(U5-SO{slash}IO1)")
			(pinfunction "SO/IO1")
			(pintype "bidirectional")
		)
		(pad "3" smd roundrect
			(at -3.9995 0.6345 270)
			(size 0.4 1.3)
			(layers "F.Cu" "F.Mask" "F.Paste")
			(roundrect_rratio 0.25)
			(net 258 "Net-(U5-*WP{slash}IO2)")
			(pinfunction "*WP/IO2")
			(pintype "bidirectional")
		)
		(pad "4" smd roundrect
			(at -3.9995 1.9045 270)
			(size 0.4 1.3)
			(layers "F.Cu" "F.Mask" "F.Paste")
			(roundrect_rratio 0.25)
			(net 5 "GND")
			(pinfunction "VSS")
			(pintype "power_in")
		)
		(pad "5" smd roundrect
			(at 3.9995 1.8755 270)
			(size 0.4 1.3)
			(layers "F.Cu" "F.Mask" "F.Paste")
			(roundrect_rratio 0.25)
			(net 259 "Net-(U5-SI{slash}IO0)")
			(pinfunction "SI/IO0")
			(pintype "bidirectional")
		)
		(pad "6" smd roundrect
			(at 3.9995 0.6035 270)
			(size 0.4 1.3)
			(layers "F.Cu" "F.Mask" "F.Paste")
			(roundrect_rratio 0.25)
			(net 256 "Net-(U5-SCK)")
			(pinfunction "SCK")
			(pintype "input")
		)
		(pad "7" smd roundrect
			(at 3.9995 -0.6655 270)
			(size 0.4 1.3)
			(layers "F.Cu" "F.Mask" "F.Paste")
			(roundrect_rratio 0.25)
			(net 257 "Net-(U5-*HOLD{slash}IO3)")
			(pinfunction "*HOLD/IO3")
			(pintype "bidirectional")
		)
		(pad "8" smd roundrect
			(at 3.9995 -1.9355 270)
			(size 0.4 1.3)
			(layers "F.Cu" "F.Mask" "F.Paste")
			(roundrect_rratio 0.25)
			(net 459 "3V3_SYS")
			(pinfunction "VCC")
			(pintype "power_in")
		)
		(pad "9" smd roundrect
			(at -0.0005 -0.0005)
			(size 4.8 4.65)
			(layers "F.Cu" "F.Mask" "F.Paste")
			(roundrect_rratio 0.05)
			(chamfer_ratio 0.1)
			(chamfer top_left)
			(net 637 "unconnected-(U5-EP-Pad9)")
			(pinfunction "EP")
			(pintype "unspecified+no_connect")
		)
	)
	(footprint "antmicro-footprints:C_0402_1005Metric"
		(layer "F.Cu")
		(at 123.14 84.724 180)
		(descr "Capacitor SMD 0402")
		(tags "capacitor SMD 0402")
		(property "Reference" "C169"
			(at 1.94 2.524 180)
			(layer "F.SilkS")
			(effects
				(font
					(size 0.7 0.7)
					(thickness 0.15)
				)
				(justify left bottom)
			)
		)
		(property "Value" "C_22u_0402"
			(at 0 1.4 180)
			(layer "F.Fab")
			(effects
				(font
					(size 0.7 0.7)
					(thickness 0.15)
				)
				(justify left bottom)
			)
		)
		(property "Description" " "
			(at 0 0 180)
			(layer "F.Fab")
			(hide yes)
			(effects
				(font
					(size 1.27 1.27)
					(thickness 0.15)
				)
			)
		)
		(property "Author" "Antmicro"
			(at 246.28 169.448 0)
			(layer "F.Fab")
			(hide yes)
			(effects
				(font
					(size 1 1)
					(thickness 0.15)
				)
			)
		)
		(property "Dielectric" ""
			(at 246.28 169.448 0)
			(layer "F.Fab")
			(hide yes)
			(effects
				(font
					(size 1 1)
					(thickness 0.15)
				)
			)
		)
		(property "License" "Apache-2.0"
			(at 246.28 169.448 0)
			(layer "F.Fab")
			(hide yes)
			(effects
				(font
					(size 1 1)
					(thickness 0.15)
				)
			)
		)
		(property "MPN" "04024W226MAT2A"
			(at 246.28 169.448 0)
			(layer "F.Fab")
			(hide yes)
			(effects
				(font
					(size 1 1)
					(thickness 0.15)
				)
			)
		)
		(property "Manufacturer" "AVX"
			(at 246.28 169.448 0)
			(layer "F.Fab")
			(hide yes)
			(effects
				(font
					(size 1 1)
					(thickness 0.15)
				)
			)
		)
		(property "Val" "22u"
			(at 246.28 169.448 0)
			(layer "F.Fab")
			(hide yes)
			(effects
				(font
					(size 1 1)
					(thickness 0.15)
				)
			)
		)
		(property "Voltage" ""
			(at 246.28 169.448 0)
			(layer "F.Fab")
			(hide yes)
			(effects
				(font
					(size 1 1)
					(thickness 0.15)
				)
			)
		)
		(sheetname "Supply")
		(sheetfile "supply.kicad_sch")
		(attr smd)
		(fp_rect
			(start -0.94 -0.47)
			(end 0.94 0.47)
			(stroke
				(width 0.05)
				(type solid)
			)
			(fill no)
			(layer "F.CrtYd")
		)
		(fp_rect
			(start -0.499 -0.249)
			(end 0.499 0.249)
			(stroke
				(width 0.15)
				(type solid)
			)
			(fill no)
			(layer "F.Fab")
		)
		(pad "1" smd roundrect
			(at -0.484 0 180)
			(size 0.59 0.64)
			(layers "F.Cu" "F.Mask" "F.Paste")
			(roundrect_rratio 0.25)
			(net 587 "/Supply/1V1_REG")
			(pintype "passive")
		)
		(pad "2" smd roundrect
			(at 0.484 0 180)
			(size 0.59 0.64)
			(layers "F.Cu" "F.Mask" "F.Paste")
			(roundrect_rratio 0.25)
			(net 5 "GND")
			(pintype "passive")
		)
	)
	(footprint "antmicro-footprints:C_0603_1608Metric"
		(layer "F.Cu")
		(at 122.3 56.35 -90)
		(descr "Capacitor SMD 0603")
		(tags "capacitor 0603")
		(property "Reference" "C185"
			(at 1.45 0.6 270)
			(layer "F.SilkS")
			(effects
				(font
					(size 0.7 0.7)
					(thickness 0.15)
				)
				(justify left bottom)
			)
		)
		(property "Value" "C_10u_25V_0603"
			(at 0 1.6 270)
			(layer "F.Fab")
			(effects
				(font
					(size 0.7 0.7)
					(thickness 0.15)
				)
				(justify left bottom)
			)
		)
		(property "Description" " "
			(at 0 0 270)
			(layer "F.Fab")
			(hide yes)
			(effects
				(font
					(size 1.27 1.27)
					(thickness 0.15)
				)
			)
		)
		(property "Author" "Antmicro"
			(at 65.95 178.65 0)
			(layer "F.Fab")
			(hide yes)
			(effects
				(font
					(size 1 1)
					(thickness 0.15)
				)
			)
		)
		(property "Dielectric" ""
			(at 65.95 178.65 0)
			(layer "F.Fab")
			(hide yes)
			(effects
				(font
					(size 1 1)
					(thickness 0.15)
				)
			)
		)
		(property "License" "Apache-2.0"
			(at 65.95 178.65 0)
			(layer "F.Fab")
			(hide yes)
			(effects
				(font
					(size 1 1)
					(thickness 0.15)
				)
			)
		)
		(property "MPN" "C1608X5R1E106M080AC"
			(at 65.95 178.65 0)
			(layer "F.Fab")
			(hide yes)
			(effects
				(font
					(size 1 1)
					(thickness 0.15)
				)
			)
		)
		(property "Manufacturer" "TDK"
			(at 65.95 178.65 0)
			(layer "F.Fab")
			(hide yes)
			(effects
				(font
					(size 1 1)
					(thickness 0.15)
				)
			)
		)
		(property "Val" "10u/25V"
			(at 65.95 178.65 0)
			(layer "F.Fab")
			(hide yes)
			(effects
				(font
					(size 1 1)
					(thickness 0.15)
				)
			)
		)
		(property "Voltage" ""
			(at 65.95 178.65 0)
			(layer "F.Fab")
			(hide yes)
			(effects
				(font
					(size 1 1)
					(thickness 0.15)
				)
			)
		)
		(sheetname "Supply")
		(sheetfile "supply.kicad_sch")
		(attr exclude_from_pos_files exclude_from_bom dnp)
		(fp_line
			(start -0.3 0.3)
			(end 0.3 0.3)
			(stroke
				(width 0.15)
				(type solid)
			)
			(layer "F.SilkS")
		)
		(fp_line
			(start -0.3 -0.3)
			(end 0.3 -0.3)
			(stroke
				(width 0.15)
				(type solid)
			)
			(layer "F.SilkS")
		)
		(fp_rect
			(start -1.24 -0.7)
			(end 1.24 0.7)
			(stroke
				(width 0.05)
				(type solid)
			)
			(fill no)
			(layer "F.CrtYd")
		)
		(fp_rect
			(start -0.8 -0.4)
			(end 0.8 0.4)
			(stroke
				(width 0.15)
				(type solid)
			)
			(fill no)
			(layer "F.Fab")
		)
		(pad "1" smd roundrect
			(at -0.7 0 270)
			(size 0.6 0.8)
			(layers "F.Cu" "F.Mask" "F.Paste")
			(roundrect_rratio 0.2)
			(net 224 "VIN")
			(pintype "passive")
		)
		(pad "2" smd roundrect
			(at 0.7 0 270)
			(size 0.6 0.8)
			(layers "F.Cu" "F.Mask" "F.Paste")
			(roundrect_rratio 0.2)
			(net 5 "GND")
			(pintype "passive")
		)
	)
)
